# T6G (Grand Teton) — schematic netlist excerpt (pin names and nets, part order shuffled) for the footprints in the layout excerpt that follows; sources: Cadence DE-HDL packaged netlist, KiCad conversion of 04192023_DAF0TMB3IC0_F0TG_MB_C_brd_V02_OCP.brd

R2987  Q_RES  0 5% EMPTY  pkg 0402LF  page 248 : A = SMB_2_BMC_GPU_R_SDA ; B = SMB_2_BMC_GPU_BUF_R_SDA
R2233  Q_RES  1K 1% EMPTY  pkg 0402LF  page 268 : A = P3V3_AUX ; B = FM_UV_ADR_TRIGGER_N
R1024  Q_RES  4.7K 5% EMPTY  pkg 0201LF  page 287 : A = P1V8_CPU0_RT_1D ; B = JTAG_TEST_MODE_RT_CPU0_P1

(kicad_pcb
	(version 20260206)
	(generator "pcbnew")
	(generator_version "10.0")
	(general
		(thickness 1.6)
		(legacy_teardrops no)
	)
	(paper "A4")
	(title_block
		(title "04192023_DAF0TMB3IC0_F0TG_MB_C_brd_V02_OCP.brd")
		(comment 1 "Grand Teton / footprints 59-61 of 8354")
	)
	(layers
		(0 "F.Cu" signal "TOP")
		(4 "In1.Cu" signal "GND")
		(6 "In2.Cu" signal "IN1")
		(8 "In3.Cu" signal "GND1")
		(10 "In4.Cu" signal "IN2")
		(12 "In5.Cu" signal "GND2")
		(14 "In6.Cu" signal "IN3")
		(16 "In7.Cu" signal "GND3")
		(18 "In8.Cu" signal "VCC")
		(20 "In9.Cu" signal "VCC1")
		(22 "In10.Cu" signal "GND4")
		(24 "In11.Cu" signal "IN4")
		(26 "In12.Cu" signal "GND5")
		(28 "In13.Cu" signal "IN5")
		(30 "In14.Cu" signal "GND6")
		(32 "In15.Cu" signal "IN6")
		(34 "In16.Cu" signal "GND7")
		(2 "B.Cu" signal "BOTTOM")
		(9 "F.Adhes" user "F.Adhesive")
		(11 "B.Adhes" user "B.Adhesive")
		(13 "F.Paste" user "Package Geometry/Pastemask Top")
		(15 "B.Paste" user "Package Geometry/Pastemask Bottom")
		(5 "F.SilkS" user "Ref Des/Silkscreen Top")
		(7 "B.SilkS" user "Ref Des/Silkscreen Bottom")
		(1 "F.Mask" user "Board Geometry/Soldermask Top")
		(3 "B.Mask" user "Board Geometry/Soldermask Bottom")
		(17 "Dwgs.User" user "User.Drawings")
		(19 "Cmts.User" user "User.Comments")
		(21 "Eco1.User" user "User.Eco1")
		(23 "Eco2.User" user "User.Eco2")
		(25 "Edge.Cuts" user "Board Geometry/Outline")
		(27 "Margin" user)
		(31 "F.CrtYd" user "Package Geometry/Place Bound Top")
		(29 "B.CrtYd" user "Package Geometry/Place Bound Bottom")
		(35 "F.Fab" user "Ref Des/Assembly Top")
		(33 "B.Fab" user "Ref Des/Assembly Bottom")
	)
	(footprint ""
		(layer "F.Cu")
		(at 335.114646 -404.873206 -90)
		(property "Reference" "R1024"
			(at 0 0 270)
			(layer "F.SilkS")
			(hide yes)
			(effects
				(font
					(size 1.27 1.27)
				)
			)
		)
		(property "Value" ""
			(at 0 0 270)
			(layer "F.Fab")
			(effects
				(font
					(size 1.27 1.27)
				)
			)
		)
		(duplicate_pad_numbers_are_jumpers no)
		(fp_line
			(start -0.32512 0.175006)
			(end -0.32512 -0.175006)
			(stroke
				(width 0.1)
				(type default)
			)
			(layer "F.Fab")
		)
		(fp_line
			(start 0.32512 0.175006)
			(end -0.32512 0.175006)
			(stroke
				(width 0.1)
				(type default)
			)
			(layer "F.Fab")
		)
		(fp_line
			(start -0.32512 -0.175006)
			(end 0.32512 -0.175006)
			(stroke
				(width 0.1)
				(type default)
			)
			(layer "F.Fab")
		)
		(fp_line
			(start 0.32512 -0.175006)
			(end 0.32512 0.175006)
			(stroke
				(width 0.1)
				(type default)
			)
			(layer "F.Fab")
		)
		(pad "1" smd rect
			(at -0.2667 0 270)
			(size 0.3048 0.381)
			(layers "F.Cu" "F.Mask" "F.Paste")
			(net "P1V8_CPU0_RT_1D")
		)
		(pad "2" smd rect
			(at 0.2667 0 90)
			(size 0.3048 0.381)
			(layers "F.Cu" "F.Mask" "F.Paste")
			(net "JTAG_TEST_MODE_RT_CPU0_P1")
		)
	)
	(footprint ""
		(layer "F.Cu")
		(at 160.441386 -117.206014 180)
		(property "Reference" "R2233"
			(at 0 0 180)
			(layer "F.SilkS")
			(hide yes)
			(effects
				(font
					(size 1.27 1.27)
				)
			)
		)
		(property "Value" ""
			(at 0 0 180)
			(layer "F.Fab")
			(effects
				(font
					(size 1.27 1.27)
				)
			)
		)
		(duplicate_pad_numbers_are_jumpers no)
		(fp_line
			(start 0.7874 0.4064)
			(end -0.7874 0.4064)
			(stroke
				(width 0.1524)
				(type default)
			)
			(layer "F.SilkS")
		)
		(fp_line
			(start 0.7874 -0.4064)
			(end 0.7874 0.4064)
			(stroke
				(width 0.1524)
				(type default)
			)
			(layer "F.SilkS")
		)
		(fp_line
			(start -0.7874 0.4064)
			(end -0.7874 -0.4064)
			(stroke
				(width 0.1524)
				(type default)
			)
			(layer "F.SilkS")
		)
		(fp_line
			(start -0.7874 -0.4064)
			(end 0.7874 -0.4064)
			(stroke
				(width 0.1524)
				(type default)
			)
			(layer "F.SilkS")
		)
		(fp_line
			(start 0.67945 0.3048)
			(end 0.120396 0.3048)
			(stroke
				(width 0.1)
				(type default)
			)
			(layer "F.Fab")
		)
		(fp_line
			(start 0.67945 -0.3048)
			(end 0.67945 0.3048)
			(stroke
				(width 0.1)
				(type default)
			)
			(layer "F.Fab")
		)
		(fp_line
			(start 0.12065 -0.2794)
			(end 0.12065 -0.3048)
			(stroke
				(width 0.1)
				(type default)
			)
			(layer "F.Fab")
		)
		(fp_line
			(start 0.12065 -0.3048)
			(end 0.67945 -0.3048)
			(stroke
				(width 0.1)
				(type default)
			)
			(layer "F.Fab")
		)
		(fp_line
			(start 0.120396 0.3048)
			(end 0.120396 0.2794)
			(stroke
				(width 0.1)
				(type default)
			)
			(layer "F.Fab")
		)
		(fp_line
			(start 0.120396 0.2794)
			(end -0.12065 0.2794)
			(stroke
				(width 0.1)
				(type default)
			)
			(layer "F.Fab")
		)
		(fp_line
			(start -0.12065 0.3048)
			(end -0.67945 0.3048)
			(stroke
				(width 0.1)
				(type default)
			)
			(layer "F.Fab")
		)
		(fp_line
			(start -0.12065 0.2794)
			(end -0.12065 0.3048)
			(stroke
				(width 0.1)
				(type default)
			)
			(layer "F.Fab")
		)
		(fp_line
			(start -0.12065 -0.2794)
			(end 0.12065 -0.2794)
			(stroke
				(width 0.1)
				(type default)
			)
			(layer "F.Fab")
		)
		(fp_line
			(start -0.12065 -0.305054)
			(end -0.12065 -0.2794)
			(stroke
				(width 0.1)
				(type default)
			)
			(layer "F.Fab")
		)
		(fp_line
			(start -0.67945 0.3048)
			(end -0.67945 -0.305054)
			(stroke
				(width 0.1)
				(type default)
			)
			(layer "F.Fab")
		)
		(fp_line
			(start -0.67945 -0.305054)
			(end -0.12065 -0.305054)
			(stroke
				(width 0.1)
				(type default)
			)
			(layer "F.Fab")
		)
		(pad "1" smd circle
			(at -0.40005 0 180)
			(size 0 0)
			(layers "F.Cu" "F.Mask" "F.Paste")
			(net "P3V3_AUX")
		)
		(pad "2" smd circle
			(at 0.40005 0 180)
			(size 0 0)
			(layers "F.Cu" "F.Mask" "F.Paste")
			(net "FM_UV_ADR_TRIGGER_N")
		)
	)
	(footprint ""
		(layer "F.Cu")
		(at 23.433278 -437.599074 -90)
		(property "Reference" "R2987"
			(at 0 0 270)
			(layer "F.SilkS")
			(hide yes)
			(effects
				(font
					(size 1.27 1.27)
				)
			)
		)
		(property "Value" ""
			(at 0 0 270)
			(layer "F.Fab")
			(effects
				(font
					(size 1.27 1.27)
				)
			)
		)
		(duplicate_pad_numbers_are_jumpers no)
		(fp_line
			(start -0.7874 0.4064)
			(end -0.7874 -0.4064)
			(stroke
				(width 0.1524)
				(type default)
			)
			(layer "F.SilkS")
		)
		(fp_line
			(start 0.7874 0.4064)
			(end -0.7874 0.4064)
			(stroke
				(width 0.1524)
				(type default)
			)
			(layer "F.SilkS")
		)
		(fp_line
			(start -0.7874 -0.4064)
			(end 0.7874 -0.4064)
			(stroke
				(width 0.1524)
				(type default)
			)
			(layer "F.SilkS")
		)
		(fp_line
			(start 0.7874 -0.4064)
			(end 0.7874 0.4064)
			(stroke
				(width 0.1524)
				(type default)
			)
			(layer "F.SilkS")
		)
		(fp_line
			(start -0.67945 0.3048)
			(end -0.67945 -0.305054)
			(stroke
				(width 0.1)
				(type default)
			)
			(layer "F.Fab")
		)
		(fp_line
			(start -0.12065 0.3048)
			(end -0.67945 0.3048)
			(stroke
				(width 0.1)
				(type default)
			)
			(layer "F.Fab")
		)
		(fp_line
			(start 0.120396 0.3048)
			(end 0.120396 0.2794)
			(stroke
				(width 0.1)
				(type default)
			)
			(layer "F.Fab")
		)
		(fp_line
			(start 0.67945 0.3048)
			(end 0.120396 0.3048)
			(stroke
				(width 0.1)
				(type default)
			)
			(layer "F.Fab")
		)
		(fp_line
			(start -0.12065 0.2794)
			(end -0.12065 0.3048)
			(stroke
				(width 0.1)
				(type default)
			)
			(layer "F.Fab")
		)
		(fp_line
			(start 0.120396 0.2794)
			(end -0.12065 0.2794)
			(stroke
				(width 0.1)
				(type default)
			)
			(layer "F.Fab")
		)
		(fp_line
			(start -0.12065 -0.2794)
			(end 0.12065 -0.2794)
			(stroke
				(width 0.1)
				(type default)
			)
			(layer "F.Fab")
		)
		(fp_line
			(start 0.12065 -0.2794)
			(end 0.12065 -0.3048)
			(stroke
				(width 0.1)
				(type default)
			)
			(layer "F.Fab")
		)
		(fp_line
			(start 0.12065 -0.3048)
			(end 0.67945 -0.3048)
			(stroke
				(width 0.1)
				(type default)
			)
			(layer "F.Fab")
		)
		(fp_line
			(start 0.67945 -0.3048)
			(end 0.67945 0.3048)
			(stroke
				(width 0.1)
				(type default)
			)
			(layer "F.Fab")
		)
		(fp_line
			(start -0.67945 -0.305054)
			(end -0.12065 -0.305054)
			(stroke
				(width 0.1)
				(type default)
			)
			(layer "F.Fab")
		)
		(fp_line
			(start -0.12065 -0.305054)
			(end -0.12065 -0.2794)
			(stroke
				(width 0.1)
				(type default)
			)
			(layer "F.Fab")
		)
		(pad "1" smd circle
			(at -0.40005 0 270)
			(size 0 0)
			(layers "F.Cu" "F.Mask" "F.Paste")
			(net "SMB_2_BMC_GPU_R_SDA")
		)
		(pad "2" smd circle
			(at 0.40005 0 270)
			(size 0 0)
			(layers "F.Cu" "F.Mask" "F.Paste")
			(net "SMB_2_BMC_GPU_BUF_R_SDA")
		)
	)
)
